(kicad_pcb
	(version 20260206)
	(generator "pcbnew")
	(generator_version "10.0")
	(general
		(thickness 0.77096)
		(legacy_teardrops no)
	)
	(paper "A4")
	(title_block
		(title "gnss-m2-neo-m9n — M2_NEO-M9N_MODULE.PcbDoc")
		(comment 1 "Time Appliance Project (Time Card) / footprints 13-22 of 40")
	)
	(layers
		(0 "F.Cu" signal "L01-Top Layer")
		(4 "In1.Cu" signal "L02-Inner Layer")
		(6 "In2.Cu" signal "L03-Inner Layer")
		(2 "B.Cu" signal "L04-Bottom Layer")
		(9 "F.Adhes" user "F.Adhesive")
		(11 "B.Adhes" user "B.Adhesive")
		(13 "F.Paste" user "Top Paste")
		(15 "B.Paste" user "Bottom Paste")
		(5 "F.SilkS" user "Top Overlay")
		(7 "B.SilkS" user "Bottom Overlay")
		(1 "F.Mask" user "Top Solder")
		(3 "B.Mask" user "Bottom Solder")
		(17 "Dwgs.User" user "User.Drawings")
		(19 "Cmts.User" user "User.Comments")
		(21 "Eco1.User" user "User.Eco1")
		(23 "Eco2.User" user "User.Eco2")
		(25 "Edge.Cuts" user)
		(27 "Margin" user)
		(31 "F.CrtYd" user "Top Courtyard")
		(29 "B.CrtYd" user "Bottom Courtyard")
		(35 "F.Fab" user "Top Component Outline")
		(33 "B.Fab" user "Bottom Component Outline 2")
	)
	(footprint "MyLibrary:c0402"
		(layer "F.Cu")
		(at 141.401105 91.7036 -90)
		(property "Reference" "C4"
			(at -0.128635 1.182557 90)
			(unlocked yes)
			(layer "F.SilkS")
			(effects
				(font
					(size 0.635 0.635)
					(thickness 0.1778)
				)
			)
		)
		(property "Value" "47pF 50V 0402"
			(at 5.192415 2.266303 270)
			(unlocked yes)
			(layer "F.SilkS")
			(hide yes)
			(effects
				(font
					(size 0.635 0.635)
					(thickness 0.1778)
				)
			)
		)
		(sheetname "01-M2_NEO-M9N_MODULE")
		(sheetfile "01-M2_NEO-M9N_MODULE.kicad_sch")
		(duplicate_pad_numbers_are_jumpers no)
		(fp_line
			(start -0.9906 0.4826)
			(end -0.9906 -0.4826)
			(stroke
				(width 0.1778)
				(type solid)
			)
			(layer "F.SilkS")
		)
		(fp_line
			(start 0.9906 0.4826)
			(end -0.9906 0.4826)
			(stroke
				(width 0.1778)
				(type solid)
			)
			(layer "F.SilkS")
		)
		(fp_line
			(start 0.9906 0.4826)
			(end 0.9906 -0.4826)
			(stroke
				(width 0.1778)
				(type solid)
			)
			(layer "F.SilkS")
		)
		(fp_line
			(start 0.9906 -0.4826)
			(end -0.9906 -0.4826)
			(stroke
				(width 0.1778)
				(type solid)
			)
			(layer "F.SilkS")
		)
		(pad "1" smd rect
			(at -0.5 0 270)
			(size 0.5 0.5)
			(layers "F.Cu" "F.Mask" "F.Paste")
			(net "RF_ANT")
		)
		(pad "2" smd rect
			(at 0.5 0 270)
			(size 0.5 0.5)
			(layers "F.Cu" "F.Mask" "F.Paste")
			(net "RF_MODULE")
		)
	)
	(footprint "MyLibrary:r0402"
		(layer "F.Cu")
		(at 154.001105 92.0036)
		(property "Reference" "R9"
			(at -0.622005 -3.177557 0)
			(unlocked yes)
			(layer "F.SilkS")
			(effects
				(font
					(size 0.635 0.635)
					(thickness 0.178)
				)
			)
		)
		(property "Value" "DNI 0 ohm 0402"
			(at 6.792115 2.200402 0)
			(unlocked yes)
			(layer "F.SilkS")
			(hide yes)
			(effects
				(font
					(size 1.524 1.524)
					(thickness 0.254)
				)
			)
		)
		(sheetname "01-M2_NEO-M9N_MODULE")
		(sheetfile "01-M2_NEO-M9N_MODULE.kicad_sch")
		(duplicate_pad_numbers_are_jumpers no)
		(fp_line
			(start -0.9906 -0.5334)
			(end 0.9906 -0.5334)
			(stroke
				(width 0.1778)
				(type solid)
			)
			(layer "F.SilkS")
		)
		(fp_line
			(start -0.9906 0.5334)
			(end -0.9906 -0.5334)
			(stroke
				(width 0.1778)
				(type solid)
			)
			(layer "F.SilkS")
		)
		(fp_line
			(start -0.9906 0.5334)
			(end 0.9906 0.5334)
			(stroke
				(width 0.1778)
				(type solid)
			)
			(layer "F.SilkS")
		)
		(fp_line
			(start 0.9906 0.5334)
			(end 0.9906 -0.5334)
			(stroke
				(width 0.1778)
				(type solid)
			)
			(layer "F.SilkS")
		)
		(pad "1" smd rect
			(at -0.5 0)
			(size 0.5 0.6)
			(layers "F.Cu" "F.Mask" "F.Paste")
			(net "NetQ1_1")
		)
		(pad "2" smd rect
			(at 0.5 0)
			(size 0.5 0.6)
			(layers "F.Cu" "F.Mask" "F.Paste")
			(net "GND")
		)
	)
	(footprint "Vault:RESC1005X40X25NL05T10"
		(layer "F.Cu")
		(at 140.601105 112.7036 90)
		(property "Reference" "R14"
			(at -0.000005 -1.795704 90)
			(unlocked yes)
			(layer "F.SilkS")
			(effects
				(font
					(face "Arial")
					(size 0.48006 0.48006)
					(thickness 0.254)
				)
			)
		)
		(property "Value" "DNI_0_5%_0402"
			(at -2.759202 9.68698 0)
			(unlocked yes)
			(layer "F.SilkS")
			(hide yes)
			(effects
				(font
					(size 1.524 1.524)
					(thickness 0.254)
				)
			)
		)
		(sheetname "02-M2_GoldFingers")
		(sheetfile "02-M2_GoldFingers.kicad_sch")
		(duplicate_pad_numbers_are_jumpers no)
		(fp_line
			(start 0.9 -0.45)
			(end 0.9 0.45)
			(stroke
				(width 0.05)
				(type solid)
			)
			(layer "F.CrtYd")
		)
		(fp_line
			(start -0.9 -0.45)
			(end 0.9 -0.45)
			(stroke
				(width 0.05)
				(type solid)
			)
			(layer "F.CrtYd")
		)
		(fp_line
			(start -0.9 -0.45)
			(end -0.9 0.45)
			(stroke
				(width 0.05)
				(type solid)
			)
			(layer "F.CrtYd")
		)
		(fp_line
			(start 0 -0.275)
			(end 0 0.275)
			(stroke
				(width 0.1)
				(type solid)
			)
			(layer "F.CrtYd")
		)
		(fp_line
			(start -0.275 0)
			(end 0.275 0)
			(stroke
				(width 0.1)
				(type solid)
			)
			(layer "F.CrtYd")
		)
		(fp_line
			(start -0.9 0.45)
			(end 0.9 0.45)
			(stroke
				(width 0.05)
				(type solid)
			)
			(layer "F.CrtYd")
		)
		(pad "1" smd rect
			(at -0.425 0 180)
			(size 0.55 0.6)
			(layers "F.Cu" "F.Mask" "F.Paste")
			(net "NetJ1_35")
		)
		(pad "2" smd rect
			(at 0.425 0 180)
			(size 0.55 0.6)
			(layers "F.Cu" "F.Mask" "F.Paste")
			(net "TP1")
		)
	)
	(footprint "MyLibrary:TP1MM"
		(layer "F.Cu")
		(at 157.601105 95.9036)
		(property "Reference" "TP7"
			(at 0.277805 1.322443 0)
			(unlocked yes)
			(layer "F.SilkS")
			(effects
				(font
					(size 0.635 0.635)
					(thickness 0.1778)
				)
			)
		)
		(property "Value" "1MM"
			(at -2.092783 1.790085 270)
			(unlocked yes)
			(layer "F.SilkS")
			(hide yes)
			(effects
				(font
					(size 0.635 0.635)
					(thickness 0.1778)
				)
			)
		)
		(sheetname "01-M2_NEO-M9N_MODULE")
		(sheetfile "01-M2_NEO-M9N_MODULE.kicad_sch")
		(duplicate_pad_numbers_are_jumpers no)
		(pad "1" smd circle
			(at 0 0)
			(size 1 1)
			(layers "F.Cu" "F.Mask" "F.Paste")
			(net "SAFEBOOT_N")
			(solder_paste_margin -100)
			(thermal_bridge_angle 90)
		)
	)
	(footprint "Vault:FP-GRM31C-0_2-e0_3_0_8-IPC_C"
		(layer "F.Cu")
		(at 154.801105 116.4036)
		(property "Reference" "C7"
			(at -2.546005 0.026921 0)
			(unlocked yes)
			(layer "F.SilkS")
			(effects
				(font
					(size 0.762 0.762)
					(thickness 0.254)
				)
			)
		)
		(property "Value" "47uF_6.3V_1206"
			(at 8.620015 2.683002 0)
			(unlocked yes)
			(layer "F.SilkS")
			(hide yes)
			(effects
				(font
					(size 1.524 1.524)
					(thickness 0.254)
				)
			)
		)
		(sheetname "02-M2_GoldFingers")
		(sheetfile "02-M2_GoldFingers.kicad_sch")
		(duplicate_pad_numbers_are_jumpers no)
		(fp_line
			(start -0.39846 -0.9)
			(end 0.39847 -0.9)
			(stroke
				(width 0.2)
				(type solid)
			)
			(layer "F.SilkS")
		)
		(fp_line
			(start -0.39846 0.9)
			(end 0.39847 0.9)
			(stroke
				(width 0.2)
				(type solid)
			)
			(layer "F.SilkS")
		)
		(fp_line
			(start -1.9531 -1)
			(end 1.9531 -1)
			(stroke
				(width 0.2)
				(type solid)
			)
			(layer "F.CrtYd")
		)
		(fp_line
			(start -1.9531 1)
			(end -1.9531 -1)
			(stroke
				(width 0.2)
				(type solid)
			)
			(layer "F.CrtYd")
		)
		(fp_line
			(start -1.9531 1)
			(end 1.9531 1)
			(stroke
				(width 0.2)
				(type solid)
			)
			(layer "F.CrtYd")
		)
		(fp_line
			(start 1.9531 1)
			(end 1.9531 -1)
			(stroke
				(width 0.2)
				(type solid)
			)
			(layer "F.CrtYd")
		)
		(fp_line
			(start -1.9531 -1)
			(end 1.9531 -1)
			(stroke
				(width 0.2)
				(type solid)
			)
			(layer "F.Fab")
		)
		(fp_line
			(start -1.9531 1)
			(end -1.9531 -1)
			(stroke
				(width 0.2)
				(type solid)
			)
			(layer "F.Fab")
		)
		(fp_line
			(start -1.9531 1)
			(end 1.9531 1)
			(stroke
				(width 0.2)
				(type solid)
			)
			(layer "F.Fab")
		)
		(fp_line
			(start -0.5 0)
			(end 0.5 0)
			(stroke
				(width 0.1)
				(type solid)
			)
			(layer "F.Fab")
		)
		(fp_line
			(start 0 0.5)
			(end 0 -0.5)
			(stroke
				(width 0.1)
				(type solid)
			)
			(layer "F.Fab")
		)
		(fp_line
			(start 1.9531 1)
			(end 1.9531 -1)
			(stroke
				(width 0.2)
				(type solid)
			)
			(layer "F.Fab")
		)
		(fp_text user "${REFERENCE}"
			(at -0.00001 0.09602 0)
			(unlocked yes)
			(layer "F.Fab")
			(effects
				(font
					(face "Arial")
					(size 0.63 0.63)
					(thickness 0.1)
				)
				(justify left bottom)
			)
		)
		(pad "1" smd rect
			(at -1.27578 0)
			(size 1.15464 1.7062)
			(layers "F.Cu" "F.Mask" "F.Paste")
			(net "+3V3")
			(solder_mask_margin 0)
			(solder_paste_margin 0)
		)
		(pad "2" smd rect
			(at 1.27578 0)
			(size 1.15464 1.7062)
			(layers "F.Cu" "F.Mask" "F.Paste")
			(net "GND")
			(solder_mask_margin 0)
			(solder_paste_margin 0)
		)
	)
	(footprint "MyLibrary:led0603"
		(layer "F.Cu")
		(at 146.039455 111.39962 90)
		(property "Reference" "LED1"
			(at 1.473577 -1.79363 360)
			(unlocked yes)
			(layer "F.SilkS")
			(effects
				(font
					(size 0.635 0.635)
					(thickness 0.1778)
				)
			)
		)
		(property "Value" "Green"
			(at -3.032593 3.262755 0)
			(unlocked yes)
			(layer "F.SilkS")
			(hide yes)
			(effects
				(font
					(size 0.635 0.635)
					(thickness 0.1778)
				)
			)
		)
		(sheetname "01-M2_NEO-M9N_MODULE")
		(sheetfile "01-M2_NEO-M9N_MODULE.kicad_sch")
		(duplicate_pad_numbers_are_jumpers no)
		(fp_line
			(start 1.397 -0.635)
			(end 1.397 0.635)
			(stroke
				(width 0.1778)
				(type solid)
			)
			(layer "F.SilkS")
		)
		(fp_line
			(start -1.397 -0.635)
			(end 1.397 -0.635)
			(stroke
				(width 0.1778)
				(type solid)
			)
			(layer "F.SilkS")
		)
		(fp_line
			(start -1.397 -0.635)
			(end -1.397 0.635)
			(stroke
				(width 0.1778)
				(type solid)
			)
			(layer "F.SilkS")
		)
		(fp_line
			(start -0.03175 -0.12065)
			(end 0.08255 -0.00635)
			(stroke
				(width 0.0762)
				(type solid)
			)
			(layer "F.SilkS")
		)
		(fp_line
			(start -0.03175 -0.12065)
			(end -0.03175 0.10795)
			(stroke
				(width 0.0762)
				(type solid)
			)
			(layer "F.SilkS")
		)
		(fp_line
			(start 0.08255 -0.00635)
			(end -0.03175 0.10795)
			(stroke
				(width 0.0762)
				(type solid)
			)
			(layer "F.SilkS")
		)
		(fp_line
			(start -1.397 0.635)
			(end 1.397 0.635)
			(stroke
				(width 0.1778)
				(type solid)
			)
			(layer "F.SilkS")
		)
		(fp_rect
			(start -0.03203 0.04853)
			(end 0.03706 -0.05242)
			(stroke
				(width 0)
				(type default)
			)
			(fill yes)
			(layer "F.SilkS")
		)
		(pad "1" smd rect
			(at -0.75 0 90)
			(size 0.8 0.8)
			(layers "F.Cu" "F.Mask" "F.Paste")
			(net "NetLED1_1")
		)
		(pad "2" smd rect
			(at 0.75 0 90)
			(size 0.8 0.8)
			(layers "F.Cu" "F.Mask" "F.Paste")
			(net "NetLED1_2")
		)
	)
	(footprint "Vault:RESC1005X40X25NL05T05"
		(layer "F.Cu")
		(at 149.501105 115.4036)
		(property "Reference" "R3"
			(at -1.322205 0.522443 0)
			(unlocked yes)
			(layer "F.SilkS")
			(effects
				(font
					(size 0.635 0.635)
					(thickness 0.1778)
				)
			)
		)
		(property "Value" "1K_1%_0402"
			(at 4.938495 2.168983 0)
			(unlocked yes)
			(layer "F.SilkS")
			(hide yes)
			(effects
				(font
					(size 0.635 0.635)
					(thickness 0.1778)
				)
			)
		)
		(sheetname "01-M2_NEO-M9N_MODULE")
		(sheetfile "01-M2_NEO-M9N_MODULE.kicad_sch")
		(duplicate_pad_numbers_are_jumpers no)
		(fp_line
			(start -0.9 -0.45)
			(end 0.9 -0.45)
			(stroke
				(width 0.05)
				(type solid)
			)
			(layer "F.CrtYd")
		)
		(fp_line
			(start -0.9 0.45)
			(end -0.9 -0.45)
			(stroke
				(width 0.05)
				(type solid)
			)
			(layer "F.CrtYd")
		)
		(fp_line
			(start -0.9 0.45)
			(end 0.9 0.45)
			(stroke
				(width 0.05)
				(type solid)
			)
			(layer "F.CrtYd")
		)
		(fp_line
			(start -0.275 0)
			(end 0.275 0)
			(stroke
				(width 0.1)
				(type solid)
			)
			(layer "F.CrtYd")
		)
		(fp_line
			(start 0 0.275)
			(end 0 -0.275)
			(stroke
				(width 0.1)
				(type solid)
			)
			(layer "F.CrtYd")
		)
		(fp_line
			(start 0.9 0.45)
			(end 0.9 -0.45)
			(stroke
				(width 0.05)
				(type solid)
			)
			(layer "F.CrtYd")
		)
		(pad "1" smd rect
			(at -0.45 0 90)
			(size 0.55 0.55)
			(layers "F.Cu" "F.Mask" "F.Paste")
			(net "GND")
		)
		(pad "2" smd rect
			(at 0.45 0 90)
			(size 0.55 0.55)
			(layers "F.Cu" "F.Mask" "F.Paste")
			(net "NetLED2_2")
		)
	)
	(footprint "MyLibrary:r0402"
		(layer "F.Cu")
		(at 151.601105 90.4036 90)
		(property "Reference" "R6"
			(at 2.178005 -0.077567 90)
			(unlocked yes)
			(layer "F.SilkS")
			(effects
				(font
					(size 0.635 0.635)
					(thickness 0.178)
				)
			)
		)
		(property "Value" "DNI 0 ohm 0402"
			(at 6.792115 2.200402 90)
			(unlocked yes)
			(layer "F.SilkS")
			(hide yes)
			(effects
				(font
					(size 1.524 1.524)
					(thickness 0.254)
				)
			)
		)
		(sheetname "01-M2_NEO-M9N_MODULE")
		(sheetfile "01-M2_NEO-M9N_MODULE.kicad_sch")
		(duplicate_pad_numbers_are_jumpers no)
		(fp_line
			(start 0.9906 -0.5334)
			(end 0.9906 0.5334)
			(stroke
				(width 0.1778)
				(type solid)
			)
			(layer "F.SilkS")
		)
		(fp_line
			(start -0.9906 -0.5334)
			(end 0.9906 -0.5334)
			(stroke
				(width 0.1778)
				(type solid)
			)
			(layer "F.SilkS")
		)
		(fp_line
			(start -0.9906 -0.5334)
			(end -0.9906 0.5334)
			(stroke
				(width 0.1778)
				(type solid)
			)
			(layer "F.SilkS")
		)
		(fp_line
			(start -0.9906 0.5334)
			(end 0.9906 0.5334)
			(stroke
				(width 0.1778)
				(type solid)
			)
			(layer "F.SilkS")
		)
		(pad "1" smd rect
			(at -0.5 0 90)
			(size 0.5 0.6)
			(layers "F.Cu" "F.Mask" "F.Paste")
			(net "NetQ1_1")
		)
		(pad "2" smd rect
			(at 0.5 0 90)
			(size 0.5 0.6)
			(layers "F.Cu" "F.Mask" "F.Paste")
			(net "+3V3")
		)
	)
	(footprint "MyLibrary:TP1MM"
		(layer "F.Cu")
		(at 152.001105 110.6036 90)
		(property "Reference" "TP10"
			(at -0.5728 1.110207 270)
			(unlocked yes)
			(layer "F.SilkS")
			(effects
				(font
					(size 0.635 0.635)
					(thickness 0.1778)
				)
			)
		)
		(property "Value" "1MM"
			(at -2.092783 1.790085 0)
			(unlocked yes)
			(layer "F.SilkS")
			(hide yes)
			(effects
				(font
					(size 0.635 0.635)
					(thickness 0.1778)
				)
			)
		)
		(sheetname "01-M2_NEO-M9N_MODULE")
		(sheetfile "01-M2_NEO-M9N_MODULE.kicad_sch")
		(duplicate_pad_numbers_are_jumpers no)
		(pad "1" smd circle
			(at 0 0 90)
			(size 1 1)
			(layers "F.Cu" "F.Mask" "F.Paste")
			(net "RX_GPS")
			(solder_paste_margin -100)
			(thermal_bridge_angle 90)
		)
	)
	(footprint "Vault:RESC1005X40X25LL05T10"
		(layer "F.Cu")
		(at 149.201105 112.7036 -90)
		(property "Reference" "R2"
			(at 0.645995 -1.126921 90)
			(unlocked yes)
			(layer "F.SilkS")
			(effects
				(font
					(size 0.762 0.762)
					(thickness 0.254)
				)
			)
		)
		(property "Value" "10K_5%_0402"
			(at 7.858675 2.251202 270)
			(unlocked yes)
			(layer "F.SilkS")
			(hide yes)
			(effects
				(font
					(size 1.524 1.524)
					(thickness 0.254)
				)
			)
		)
		(sheetname "01-M2_NEO-M9N_MODULE")
		(sheetfile "01-M2_NEO-M9N_MODULE.kicad_sch")
		(duplicate_pad_numbers_are_jumpers no)
		(fp_line
			(start -0.75 0.4)
			(end -0.75 -0.4)
			(stroke
				(width 0.05)
				(type solid)
			)
			(layer "F.CrtYd")
		)
		(fp_line
			(start 0.75 0.4)
			(end -0.75 0.4)
			(stroke
				(width 0.05)
				(type solid)
			)
			(layer "F.CrtYd")
		)
		(fp_line
			(start 0.75 0.4)
			(end 0.75 -0.4)
			(stroke
				(width 0.05)
				(type solid)
			)
			(layer "F.CrtYd")
		)
		(fp_line
			(start 0 0.275)
			(end 0 -0.275)
			(stroke
				(width 0.1)
				(type solid)
			)
			(layer "F.CrtYd")
		)
		(fp_line
			(start 0.275 0)
			(end -0.275 0)
			(stroke
				(width 0.1)
				(type solid)
			)
			(layer "F.CrtYd")
		)
		(fp_line
			(start 0.75 -0.4)
			(end -0.75 -0.4)
			(stroke
				(width 0.05)
				(type solid)
			)
			(layer "F.CrtYd")
		)
		(pad "1" smd rect
			(at -0.375 0)
			(size 0.45 0.5)
			(layers "F.Cu" "F.Mask" "F.Paste")
			(net "SCL")
		)
		(pad "2" smd rect
			(at 0.375 0)
			(size 0.45 0.5)
			(layers "F.Cu" "F.Mask" "F.Paste")
			(net "+3V3")
		)
	)
)
